# T6G (Grand Teton) — schematic netlist excerpt (pin names and nets, part order shuffled) for the footprints in the layout excerpt that follows; sources: Cadence DE-HDL packaged netlist, KiCad conversion of 04192023_DAF0TMB3IC0_F0TG_MB_C_brd_V02_OCP.brd

R429  Q_RES  0 5% CHIP  pkg 0402LF  page 159 : A = I3C_1_SPD_DDRGL_CPU0_SDA ; B = I3C_1_SPD_DDRGL_CPU0_R_SDA
C501  Q_CAP  22UF 4V 20% X6S  pkg C0402  page 356 : A = P0V9_CPU1_RT3_2A ; B = GND

(kicad_pcb
	(version 20260206)
	(generator "pcbnew")
	(generator_version "10.0")
	(general
		(thickness 1.6)
		(legacy_teardrops no)
	)
	(paper "A4")
	(title_block
		(title "04192023_DAF0TMB3IC0_F0TG_MB_C_brd_V02_OCP.brd")
		(comment 1 "Grand Teton / footprints 6163-6164 of 8354")
	)
	(layers
		(0 "F.Cu" signal "TOP")
		(4 "In1.Cu" signal "GND")
		(6 "In2.Cu" signal "IN1")
		(8 "In3.Cu" signal "GND1")
		(10 "In4.Cu" signal "IN2")
		(12 "In5.Cu" signal "GND2")
		(14 "In6.Cu" signal "IN3")
		(16 "In7.Cu" signal "GND3")
		(18 "In8.Cu" signal "VCC")
		(20 "In9.Cu" signal "VCC1")
		(22 "In10.Cu" signal "GND4")
		(24 "In11.Cu" signal "IN4")
		(26 "In12.Cu" signal "GND5")
		(28 "In13.Cu" signal "IN5")
		(30 "In14.Cu" signal "GND6")
		(32 "In15.Cu" signal "IN6")
		(34 "In16.Cu" signal "GND7")
		(2 "B.Cu" signal "BOTTOM")
		(9 "F.Adhes" user "F.Adhesive")
		(11 "B.Adhes" user "B.Adhesive")
		(13 "F.Paste" user "Package Geometry/Pastemask Top")
		(15 "B.Paste" user "Package Geometry/Pastemask Bottom")
		(5 "F.SilkS" user "Ref Des/Silkscreen Top")
		(7 "B.SilkS" user "Ref Des/Silkscreen Bottom")
		(1 "F.Mask" user "Board Geometry/Soldermask Top")
		(3 "B.Mask" user "Board Geometry/Soldermask Bottom")
		(17 "Dwgs.User" user "User.Drawings")
		(19 "Cmts.User" user "User.Comments")
		(21 "Eco1.User" user "User.Eco1")
		(23 "Eco2.User" user "User.Eco2")
		(25 "Edge.Cuts" user "Board Geometry/Outline")
		(27 "Margin" user)
		(31 "F.CrtYd" user "Package Geometry/Place Bound Top")
		(29 "B.CrtYd" user "Package Geometry/Place Bound Bottom")
		(35 "F.Fab" user "Ref Des/Assembly Top")
		(33 "B.Fab" user "Ref Des/Assembly Bottom")
	)
	(footprint ""
		(layer "B.Cu")
		(at 130.09118 -390.560052 90)
		(property "Reference" "C501"
			(at 0 0 90)
			(layer "B.SilkS")
			(hide yes)
			(effects
				(font
					(size 1.27 1.27)
				)
				(justify mirror)
			)
		)
		(property "Value" ""
			(at 0 0 90)
			(layer "B.Fab")
			(effects
				(font
					(size 1.27 1.27)
				)
				(justify mirror)
			)
		)
		(duplicate_pad_numbers_are_jumpers no)
		(fp_line
			(start 0.7874 -0.4064)
			(end -0.7874 -0.4064)
			(stroke
				(width 0.1524)
				(type default)
			)
			(layer "B.SilkS")
		)
		(fp_line
			(start -0.7874 -0.4064)
			(end -0.7874 0.4064)
			(stroke
				(width 0.1524)
				(type default)
			)
			(layer "B.SilkS")
		)
		(fp_line
			(start 0.7874 0.4064)
			(end 0.7874 -0.4064)
			(stroke
				(width 0.1524)
				(type default)
			)
			(layer "B.SilkS")
		)
		(fp_line
			(start -0.7874 0.4064)
			(end 0.7874 0.4064)
			(stroke
				(width 0.1524)
				(type default)
			)
			(layer "B.SilkS")
		)
		(fp_line
			(start 0.67945 -0.305054)
			(end 0.12065 -0.305054)
			(stroke
				(width 0.1)
				(type default)
			)
			(layer "B.Fab")
		)
		(fp_line
			(start 0.12065 -0.305054)
			(end 0.12065 -0.2794)
			(stroke
				(width 0.1)
				(type default)
			)
			(layer "B.Fab")
		)
		(fp_line
			(start -0.12065 -0.3048)
			(end -0.67945 -0.3048)
			(stroke
				(width 0.1)
				(type default)
			)
			(layer "B.Fab")
		)
		(fp_line
			(start -0.67945 -0.3048)
			(end -0.67945 0.3048)
			(stroke
				(width 0.1)
				(type default)
			)
			(layer "B.Fab")
		)
		(fp_line
			(start 0.12065 -0.2794)
			(end -0.12065 -0.2794)
			(stroke
				(width 0.1)
				(type default)
			)
			(layer "B.Fab")
		)
		(fp_line
			(start -0.12065 -0.2794)
			(end -0.12065 -0.3048)
			(stroke
				(width 0.1)
				(type default)
			)
			(layer "B.Fab")
		)
		(fp_line
			(start 0.12065 0.2794)
			(end 0.12065 0.3048)
			(stroke
				(width 0.1)
				(type default)
			)
			(layer "B.Fab")
		)
		(fp_line
			(start -0.120396 0.2794)
			(end 0.12065 0.2794)
			(stroke
				(width 0.1)
				(type default)
			)
			(layer "B.Fab")
		)
		(fp_line
			(start 0.67945 0.3048)
			(end 0.67945 -0.305054)
			(stroke
				(width 0.1)
				(type default)
			)
			(layer "B.Fab")
		)
		(fp_line
			(start 0.12065 0.3048)
			(end 0.67945 0.3048)
			(stroke
				(width 0.1)
				(type default)
			)
			(layer "B.Fab")
		)
		(fp_line
			(start -0.120396 0.3048)
			(end -0.120396 0.2794)
			(stroke
				(width 0.1)
				(type default)
			)
			(layer "B.Fab")
		)
		(fp_line
			(start -0.67945 0.3048)
			(end -0.120396 0.3048)
			(stroke
				(width 0.1)
				(type default)
			)
			(layer "B.Fab")
		)
		(pad "1" smd circle
			(at 0.40005 0 270)
			(size 0 0)
			(layers "B.Cu" "B.Mask" "B.Paste")
			(net "P0V9_CPU1_RT3_2A")
		)
		(pad "2" smd circle
			(at -0.40005 0 270)
			(size 0 0)
			(layers "B.Cu" "B.Mask" "B.Paste")
			(net "GND")
		)
	)
	(footprint ""
		(layer "B.Cu")
		(at 383.076958 -205.101952 -90)
		(property "Reference" "R429"
			(at 0 0 90)
			(layer "B.SilkS")
			(hide yes)
			(effects
				(font
					(size 1.27 1.27)
				)
				(justify mirror)
			)
		)
		(property "Value" ""
			(at 0 0 90)
			(layer "B.Fab")
			(effects
				(font
					(size 1.27 1.27)
				)
				(justify mirror)
			)
		)
		(duplicate_pad_numbers_are_jumpers no)
		(fp_line
			(start -0.7874 0.4064)
			(end 0.7874 0.4064)
			(stroke
				(width 0.1524)
				(type default)
			)
			(layer "B.SilkS")
		)
		(fp_line
			(start 0.7874 0.4064)
			(end 0.7874 -0.4064)
			(stroke
				(width 0.1524)
				(type default)
			)
			(layer "B.SilkS")
		)
		(fp_line
			(start -0.7874 -0.4064)
			(end -0.7874 0.4064)
			(stroke
				(width 0.1524)
				(type default)
			)
			(layer "B.SilkS")
		)
		(fp_line
			(start 0.7874 -0.4064)
			(end -0.7874 -0.4064)
			(stroke
				(width 0.1524)
				(type default)
			)
			(layer "B.SilkS")
		)
		(fp_line
			(start -0.67945 0.3048)
			(end -0.120396 0.3048)
			(stroke
				(width 0.1)
				(type default)
			)
			(layer "B.Fab")
		)
		(fp_line
			(start -0.120396 0.3048)
			(end -0.120396 0.2794)
			(stroke
				(width 0.1)
				(type default)
			)
			(layer "B.Fab")
		)
		(fp_line
			(start 0.12065 0.3048)
			(end 0.67945 0.3048)
			(stroke
				(width 0.1)
				(type default)
			)
			(layer "B.Fab")
		)
		(fp_line
			(start 0.67945 0.3048)
			(end 0.67945 -0.305054)
			(stroke
				(width 0.1)
				(type default)
			)
			(layer "B.Fab")
		)
		(fp_line
			(start -0.120396 0.2794)
			(end 0.12065 0.2794)
			(stroke
				(width 0.1)
				(type default)
			)
			(layer "B.Fab")
		)
		(fp_line
			(start 0.12065 0.2794)
			(end 0.12065 0.3048)
			(stroke
				(width 0.1)
				(type default)
			)
			(layer "B.Fab")
		)
		(fp_line
			(start -0.12065 -0.2794)
			(end -0.12065 -0.3048)
			(stroke
				(width 0.1)
				(type default)
			)
			(layer "B.Fab")
		)
		(fp_line
			(start 0.12065 -0.2794)
			(end -0.12065 -0.2794)
			(stroke
				(width 0.1)
				(type default)
			)
			(layer "B.Fab")
		)
		(fp_line
			(start -0.67945 -0.3048)
			(end -0.67945 0.3048)
			(stroke
				(width 0.1)
				(type default)
			)
			(layer "B.Fab")
		)
		(fp_line
			(start -0.12065 -0.3048)
			(end -0.67945 -0.3048)
			(stroke
				(width 0.1)
				(type default)
			)
			(layer "B.Fab")
		)
		(fp_line
			(start 0.12065 -0.305054)
			(end 0.12065 -0.2794)
			(stroke
				(width 0.1)
				(type default)
			)
			(layer "B.Fab")
		)
		(fp_line
			(start 0.67945 -0.305054)
			(end 0.12065 -0.305054)
			(stroke
				(width 0.1)
				(type default)
			)
			(layer "B.Fab")
		)
		(pad "1" smd rect
			(at 0.40005 0 270)
			(size 0.4572 0.508)
			(layers "B.Cu" "B.Mask" "B.Paste")
			(net "I3C_1_SPD_DDRGL_CPU0_SDA")
		)
		(pad "2" smd rect
			(at -0.40005 0 270)
			(size 0.4572 0.508)
			(layers "B.Cu" "B.Mask" "B.Paste")
			(net "I3C_1_SPD_DDRGL_CPU0_R_SDA")
		)
	)
)
